(kicad_pcb
	(version 20221018)
	(generator pcbnew)
	(general
    (thickness 1.62)
  )
	(paper "A4")
	(title_block
    (title "ECP5 - Datacenter Secure Control Module (DC-SCM)")
    (date "2024-07-01")
    (rev "1.2.1")
		(comment 9 "footprints 384-391 of 506")
	)
	(layers
    (0 "F.Cu" signal)
    (1 "In1.Cu" power)
    (2 "In2.Cu" signal)
    (3 "In3.Cu" power)
    (4 "In4.Cu" power)
    (5 "In5.Cu" signal)
    (6 "In6.Cu" power)
    (31 "B.Cu" signal)
    (32 "B.Adhes" user "B.Adhesive")
    (33 "F.Adhes" user "F.Adhesive")
    (34 "B.Paste" user)
    (35 "F.Paste" user)
    (36 "B.SilkS" user "B.Silkscreen")
    (37 "F.SilkS" user "F.Silkscreen")
    (38 "B.Mask" user)
    (39 "F.Mask" user)
    (40 "Dwgs.User" user "User.Drawings")
    (41 "Cmts.User" user "User.Comments")
    (42 "Eco1.User" user "User.Eco1")
    (43 "Eco2.User" user "User.Eco2")
    (44 "Edge.Cuts" user)
    (45 "Margin" user)
    (46 "B.CrtYd" user "B.Courtyard")
    (47 "F.CrtYd" user "F.Courtyard")
    (48 "B.Fab" user)
    (49 "F.Fab" user)
  )
	(footprint "antmicro-footprints:C_0402_1005Metric" (layer "B.Cu")
    (at 104.45 90.55 -90)
    (descr "Capacitor SMD 0402")
    (tags "capacitor SMD 0402")
    (property "Author" "Antmicro")
    (property "Dielectric" "X7R")
    (property "License" "Apache-2.0")
    (property "MPN" "GRM155R71H103KA88D")
    (property "Manufacturer" "Murata")
    (property "Public" "False")
    (property "Sheetfile" "ethernet.kicad_sch")
    (property "Sheetname" "Ethernet")
    (property "Val" "10n")
    (property "Voltage" "50V")
    (property "ki_description" "SMD Multilayer Ceramic Capacitor, 10000 pF, 50 V, 0402 [1005 Metric], ± 10%, X7R, GRM Series")
    (property "ki_keywords" "0402, SMT, CAPACITOR, PASSIVE")
    (attr smd)
    (fp_text reference "C23" (at -1.885 -0.05 90) (layer "B.SilkS")
        (effects (font (size 0.7 0.7) (thickness 0.127)) (justify mirror))
    )
    (fp_text value "C_10n_0402" (at 0 -1.17 90) (layer "B.Fab")
        (effects (font (size 1 1) (thickness 0.15)) (justify mirror))
    )
    (fp_text user "Author: Antmicro" (at -0.939 -3.399 90) (layer "B.Fab") hide
        (effects (font (size 0.7 0.7) (thickness 0.15)) (justify left bottom mirror))
    )
    (fp_text user "License: Apache-2.0" (at -0.939 -5.799 90) (layer "B.Fab") hide
        (effects (font (size 0.7 0.7) (thickness 0.15)) (justify left bottom mirror))
    )
    (fp_text user "${REFERENCE}" (at 0 0 90) (layer "B.Fab")
        (effects (font (size 0.25 0.25) (thickness 0.04)) (justify mirror))
    )
    (fp_rect (start -0.925 0.47) (end 0.925 -0.47)
      (stroke (width 0.05) (type default)) (fill none) (layer "B.CrtYd"))
    (fp_line (start -0.494 -0.248) (end -0.494 0.25)
      (stroke (width 0.15) (type solid)) (layer "B.Fab"))
    (fp_line (start -0.494 0.25) (end 0.504 0.25)
      (stroke (width 0.15) (type solid)) (layer "B.Fab"))
    (fp_line (start 0.504 -0.248) (end -0.494 -0.248)
      (stroke (width 0.15) (type solid)) (layer "B.Fab"))
    (fp_line (start 0.504 0.25) (end 0.504 -0.248)
      (stroke (width 0.15) (type solid)) (layer "B.Fab"))
    (pad "1" smd roundrect (at -0.48 0 270) (size 0.59 0.64) (layers "B.Cu" "B.Paste" "B.Mask") (roundrect_rratio 0.25)
      (net 1 "GND") (pintype "passive"))
    (pad "2" smd roundrect (at 0.48 0 270) (size 0.59 0.64) (layers "B.Cu" "B.Paste" "B.Mask") (roundrect_rratio 0.25)
      (net 9 "/Ethernet/AVDDL") (pintype "passive"))
  )
	(footprint "antmicro-footprints:C_0402_1005Metric" (layer "B.Cu")
    (at 102.01 100.3 -90)
    (descr "Capacitor SMD 0402")
    (tags "capacitor SMD 0402")
    (property "Author" "Antmicro")
    (property "Dielectric" "")
    (property "License" "Apache-2.0")
    (property "MPN" "GRM155R61A475MEAAD")
    (property "Manufacturer" "Murata")
    (property "Public" "False")
    (property "Sheetfile" "ethernet.kicad_sch")
    (property "Sheetname" "Ethernet")
    (property "Val" "4u7")
    (property "Voltage" "")
    (property "ki_description" "SMD Multilayer Ceramic Capacitor, 4.7 µF, 10 V, 0402 [1005 Metric], ± 20%, X5R, GRM Series")
    (property "ki_keywords" "0402, SMT, CAPACITOR, PASSIVE")
    (attr smd)
    (fp_text reference "C1" (at 1.575 -0.05 90) (layer "B.SilkS")
        (effects (font (size 0.7 0.7) (thickness 0.127)) (justify mirror))
    )
    (fp_text value "C_4u7_0402" (at 0 -1.17 90) (layer "B.Fab")
        (effects (font (size 1 1) (thickness 0.15)) (justify mirror))
    )
    (fp_text user "Author: Antmicro" (at -0.939 -3.399 90) (layer "B.Fab") hide
        (effects (font (size 0.7 0.7) (thickness 0.15)) (justify left bottom mirror))
    )
    (fp_text user "License: Apache-2.0" (at -0.939 -5.799 90) (layer "B.Fab") hide
        (effects (font (size 0.7 0.7) (thickness 0.15)) (justify left bottom mirror))
    )
    (fp_text user "${REFERENCE}" (at 0 0 90) (layer "B.Fab")
        (effects (font (size 0.25 0.25) (thickness 0.04)) (justify mirror))
    )
    (fp_rect (start -0.925 0.47) (end 0.925 -0.47)
      (stroke (width 0.05) (type default)) (fill none) (layer "B.CrtYd"))
    (fp_line (start -0.494 -0.248) (end -0.494 0.25)
      (stroke (width 0.15) (type solid)) (layer "B.Fab"))
    (fp_line (start -0.494 0.25) (end 0.504 0.25)
      (stroke (width 0.15) (type solid)) (layer "B.Fab"))
    (fp_line (start 0.504 -0.248) (end -0.494 -0.248)
      (stroke (width 0.15) (type solid)) (layer "B.Fab"))
    (fp_line (start 0.504 0.25) (end 0.504 -0.248)
      (stroke (width 0.15) (type solid)) (layer "B.Fab"))
    (pad "1" smd roundrect (at -0.48 0 270) (size 0.59 0.64) (layers "B.Cu" "B.Paste" "B.Mask") (roundrect_rratio 0.25)
      (net 1 "GND") (pintype "passive"))
    (pad "2" smd roundrect (at 0.48 0 270) (size 0.59 0.64) (layers "B.Cu" "B.Paste" "B.Mask") (roundrect_rratio 0.25)
      (net 211 "VCC1V2") (pintype "passive"))
  )
	(footprint "antmicro-footprints:C_0402_1005Metric" (layer "B.Cu")
    (at 108.95 96.7)
    (descr "Capacitor SMD 0402")
    (tags "capacitor SMD 0402")
    (property "Author" "Antmicro")
    (property "Dielectric" "X5R")
    (property "License" "Apache-2.0")
    (property "MPN" "GRM155R61H104KE14D")
    (property "Manufacturer" "Murata")
    (property "Public" "False")
    (property "Sheetfile" "ethernet.kicad_sch")
    (property "Sheetname" "Ethernet")
    (property "Val" "100n")
    (property "Voltage" "50V")
    (property "ki_description" "SMD Multilayer Ceramic Capacitor, 0.1 µF, 50 V, 0402 [1005 Metric], ± 10%, X5R, GRM Series")
    (property "ki_keywords" "0402, SMT, CAPACITOR, PASSIVE, CERAMIC, MLCC")
    (attr smd)
    (fp_text reference "C47" (at 0.1 4.935) (layer "B.SilkS")
        (effects (font (size 0.7 0.7) (thickness 0.127)) (justify mirror))
    )
    (fp_text value "C_100n_0402" (at 0 -1.17) (layer "B.Fab")
        (effects (font (size 1 1) (thickness 0.15)) (justify mirror))
    )
    (fp_text user "${REFERENCE}" (at 0 0) (layer "B.Fab")
        (effects (font (size 0.25 0.25) (thickness 0.04)) (justify mirror))
    )
    (fp_text user "License: Apache-2.0" (at -0.939 -5.799 180) (layer "B.Fab") hide
        (effects (font (size 0.7 0.7) (thickness 0.15)) (justify left bottom mirror))
    )
    (fp_text user "Author: Antmicro" (at -0.939 -3.399 180) (layer "B.Fab") hide
        (effects (font (size 0.7 0.7) (thickness 0.15)) (justify left bottom mirror))
    )
    (fp_rect (start -0.925 0.47) (end 0.925 -0.47)
      (stroke (width 0.05) (type default)) (fill none) (layer "B.CrtYd"))
    (fp_line (start -0.494 -0.248) (end -0.494 0.25)
      (stroke (width 0.15) (type solid)) (layer "B.Fab"))
    (fp_line (start -0.494 0.25) (end 0.504 0.25)
      (stroke (width 0.15) (type solid)) (layer "B.Fab"))
    (fp_line (start 0.504 -0.248) (end -0.494 -0.248)
      (stroke (width 0.15) (type solid)) (layer "B.Fab"))
    (fp_line (start 0.504 0.25) (end 0.504 -0.248)
      (stroke (width 0.15) (type solid)) (layer "B.Fab"))
    (pad "1" smd roundrect (at -0.48 0) (size 0.59 0.64) (layers "B.Cu" "B.Paste" "B.Mask") (roundrect_rratio 0.25)
      (net 163 "ETH_~{RESET}") (pintype "passive"))
    (pad "2" smd roundrect (at 0.48 0) (size 0.59 0.64) (layers "B.Cu" "B.Paste" "B.Mask") (roundrect_rratio 0.25)
      (net 1 "GND") (pintype "passive"))
  )
	(footprint "antmicro-footprints:C_0402_1005Metric" (layer "B.Cu")
    (at 129.65 114)
    (descr "Capacitor SMD 0402")
    (tags "capacitor SMD 0402")
    (property "Author" "Antmicro")
    (property "Dielectric" "X5R")
    (property "License" "Apache-2.0")
    (property "MPN" "GRM155R61H104KE14D")
    (property "Manufacturer" "Murata")
    (property "Public" "False")
    (property "Sheetfile" "interfaces.kicad_sch")
    (property "Sheetname" "Interfaces")
    (property "Val" "100n")
    (property "Voltage" "50V")
    (property "ki_description" "SMD Multilayer Ceramic Capacitor, 0.1 µF, 50 V, 0402 [1005 Metric], ± 10%, X5R, GRM Series")
    (property "ki_keywords" "0402, SMT, CAPACITOR, PASSIVE, CERAMIC, MLCC")
    (attr smd)
    (fp_text reference "C69" (at -2 0) (layer "B.SilkS")
        (effects (font (size 0.7 0.7) (thickness 0.127)) (justify mirror))
    )
    (fp_text value "C_100n_0402" (at 0 -1.17) (layer "B.Fab")
        (effects (font (size 1 1) (thickness 0.15)) (justify mirror))
    )
    (fp_text user "License: Apache-2.0" (at -0.939 -5.799 180) (layer "B.Fab") hide
        (effects (font (size 0.7 0.7) (thickness 0.15)) (justify left bottom mirror))
    )
    (fp_text user "${REFERENCE}" (at 0 0) (layer "B.Fab")
        (effects (font (size 0.25 0.25) (thickness 0.04)) (justify mirror))
    )
    (fp_text user "Author: Antmicro" (at -0.939 -3.399 180) (layer "B.Fab") hide
        (effects (font (size 0.7 0.7) (thickness 0.15)) (justify left bottom mirror))
    )
    (fp_rect (start -0.925 0.47) (end 0.925 -0.47)
      (stroke (width 0.05) (type default)) (fill none) (layer "B.CrtYd"))
    (fp_line (start -0.494 -0.248) (end -0.494 0.25)
      (stroke (width 0.15) (type solid)) (layer "B.Fab"))
    (fp_line (start -0.494 0.25) (end 0.504 0.25)
      (stroke (width 0.15) (type solid)) (layer "B.Fab"))
    (fp_line (start 0.504 -0.248) (end -0.494 -0.248)
      (stroke (width 0.15) (type solid)) (layer "B.Fab"))
    (fp_line (start 0.504 0.25) (end 0.504 -0.248)
      (stroke (width 0.15) (type solid)) (layer "B.Fab"))
    (pad "1" smd roundrect (at -0.48 0) (size 0.59 0.64) (layers "B.Cu" "B.Paste" "B.Mask") (roundrect_rratio 0.25)
      (net 2 "VCC3V3") (pintype "passive"))
    (pad "2" smd roundrect (at 0.48 0) (size 0.59 0.64) (layers "B.Cu" "B.Paste" "B.Mask") (roundrect_rratio 0.25)
      (net 1 "GND") (pintype "passive"))
  )
	(footprint "antmicro-footprints:C_0402_1005Metric" (layer "B.Cu")
    (at 121.55 115.8 -90)
    (descr "Capacitor SMD 0402")
    (tags "capacitor SMD 0402")
    (property "Author" "Antmicro")
    (property "Dielectric" "X5R")
    (property "License" "Apache-2.0")
    (property "MPN" "GRM155R61H104KE14D")
    (property "Manufacturer" "Murata")
    (property "Public" "False")
    (property "Sheetfile" "interfaces.kicad_sch")
    (property "Sheetname" "Interfaces")
    (property "Val" "100n")
    (property "Voltage" "50V")
    (property "ki_description" "SMD Multilayer Ceramic Capacitor, 0.1 µF, 50 V, 0402 [1005 Metric], ± 10%, X5R, GRM Series")
    (property "ki_keywords" "0402, SMT, CAPACITOR, PASSIVE, CERAMIC, MLCC")
    (attr smd)
    (fp_text reference "C76" (at -0.025 1.05 90) (layer "B.SilkS")
        (effects (font (size 0.7 0.7) (thickness 0.127)) (justify mirror))
    )
    (fp_text value "C_100n_0402" (at 0 -1.17 90) (layer "B.Fab")
        (effects (font (size 1 1) (thickness 0.15)) (justify mirror))
    )
    (fp_text user "Author: Antmicro" (at -0.939 -3.399 90) (layer "B.Fab") hide
        (effects (font (size 0.7 0.7) (thickness 0.15)) (justify left bottom mirror))
    )
    (fp_text user "License: Apache-2.0" (at -0.939 -5.799 90) (layer "B.Fab") hide
        (effects (font (size 0.7 0.7) (thickness 0.15)) (justify left bottom mirror))
    )
    (fp_text user "${REFERENCE}" (at 0 0 90) (layer "B.Fab")
        (effects (font (size 0.25 0.25) (thickness 0.04)) (justify mirror))
    )
    (fp_rect (start -0.925 0.47) (end 0.925 -0.47)
      (stroke (width 0.05) (type default)) (fill none) (layer "B.CrtYd"))
    (fp_line (start -0.494 -0.248) (end -0.494 0.25)
      (stroke (width 0.15) (type solid)) (layer "B.Fab"))
    (fp_line (start -0.494 0.25) (end 0.504 0.25)
      (stroke (width 0.15) (type solid)) (layer "B.Fab"))
    (fp_line (start 0.504 -0.248) (end -0.494 -0.248)
      (stroke (width 0.15) (type solid)) (layer "B.Fab"))
    (fp_line (start 0.504 0.25) (end 0.504 -0.248)
      (stroke (width 0.15) (type solid)) (layer "B.Fab"))
    (pad "1" smd roundrect (at -0.48 0 270) (size 0.59 0.64) (layers "B.Cu" "B.Paste" "B.Mask") (roundrect_rratio 0.25)
      (net 1 "GND") (pintype "passive"))
    (pad "2" smd roundrect (at 0.48 0 270) (size 0.59 0.64) (layers "B.Cu" "B.Paste" "B.Mask") (roundrect_rratio 0.25)
      (net 672 "Net-(C76-Pad2)") (pintype "passive"))
  )
	(footprint "antmicro-footprints:C_0402_1005Metric" (layer "B.Cu")
    (at 129.65 116.533333)
    (descr "Capacitor SMD 0402")
    (tags "capacitor SMD 0402")
    (property "Author" "Antmicro")
    (property "Dielectric" "")
    (property "License" "Apache-2.0")
    (property "MPN" "GRM155R61A475MEAAD")
    (property "Manufacturer" "Murata")
    (property "Public" "False")
    (property "Sheetfile" "interfaces.kicad_sch")
    (property "Sheetname" "Interfaces")
    (property "Val" "4u7")
    (property "Voltage" "")
    (property "ki_description" "SMD Multilayer Ceramic Capacitor, 4.7 µF, 10 V, 0402 [1005 Metric], ± 20%, X5R, GRM Series")
    (property "ki_keywords" "0402, SMT, CAPACITOR, PASSIVE")
    (attr smd)
    (fp_text reference "C70" (at 2 -0.008333) (layer "B.SilkS")
        (effects (font (size 0.7 0.7) (thickness 0.127)) (justify mirror))
    )
    (fp_text value "C_4u7_0402" (at 0 -1.17) (layer "B.Fab")
        (effects (font (size 1 1) (thickness 0.15)) (justify mirror))
    )
    (fp_text user "Author: Antmicro" (at -0.939 -3.399 180) (layer "B.Fab") hide
        (effects (font (size 0.7 0.7) (thickness 0.15)) (justify left bottom mirror))
    )
    (fp_text user "License: Apache-2.0" (at -0.939 -5.799 180) (layer "B.Fab") hide
        (effects (font (size 0.7 0.7) (thickness 0.15)) (justify left bottom mirror))
    )
    (fp_text user "${REFERENCE}" (at 0 0) (layer "B.Fab")
        (effects (font (size 0.25 0.25) (thickness 0.04)) (justify mirror))
    )
    (fp_rect (start -0.925 0.47) (end 0.925 -0.47)
      (stroke (width 0.05) (type default)) (fill none) (layer "B.CrtYd"))
    (fp_line (start -0.494 -0.248) (end -0.494 0.25)
      (stroke (width 0.15) (type solid)) (layer "B.Fab"))
    (fp_line (start -0.494 0.25) (end 0.504 0.25)
      (stroke (width 0.15) (type solid)) (layer "B.Fab"))
    (fp_line (start 0.504 -0.248) (end -0.494 -0.248)
      (stroke (width 0.15) (type solid)) (layer "B.Fab"))
    (fp_line (start 0.504 0.25) (end 0.504 -0.248)
      (stroke (width 0.15) (type solid)) (layer "B.Fab"))
    (pad "1" smd roundrect (at -0.48 0) (size 0.59 0.64) (layers "B.Cu" "B.Paste" "B.Mask") (roundrect_rratio 0.25)
      (net 226 "Net-(U9-VDDA1.8)") (pintype "passive"))
    (pad "2" smd roundrect (at 0.48 0) (size 0.59 0.64) (layers "B.Cu" "B.Paste" "B.Mask") (roundrect_rratio 0.25)
      (net 1 "GND") (pintype "passive"))
  )
	(footprint "antmicro-footprints:C_0402_1005Metric" (layer "B.Cu")
    (at 129.65 117.541666 180)
    (descr "Capacitor SMD 0402")
    (tags "capacitor SMD 0402")
    (property "Author" "Antmicro")
    (property "Dielectric" "")
    (property "License" "Apache-2.0")
    (property "MPN" "GRM155R61A475MEAAD")
    (property "Manufacturer" "Murata")
    (property "Public" "False")
    (property "Sheetfile" "interfaces.kicad_sch")
    (property "Sheetname" "Interfaces")
    (property "Val" "4u7")
    (property "Voltage" "")
    (property "ki_description" "SMD Multilayer Ceramic Capacitor, 4.7 µF, 10 V, 0402 [1005 Metric], ± 20%, X5R, GRM Series")
    (property "ki_keywords" "0402, SMT, CAPACITOR, PASSIVE")
    (attr smd)
    (fp_text reference "C77" (at 2 0.008334) (layer "B.SilkS")
        (effects (font (size 0.7 0.7) (thickness 0.127)) (justify mirror))
    )
    (fp_text value "C_4u7_0402" (at 0 -1.17) (layer "B.Fab")
        (effects (font (size 1 1) (thickness 0.15)) (justify mirror))
    )
    (fp_text user "Author: Antmicro" (at -0.939 -3.399) (layer "B.Fab") hide
        (effects (font (size 0.7 0.7) (thickness 0.15)) (justify left bottom mirror))
    )
    (fp_text user "${REFERENCE}" (at 0 0) (layer "B.Fab")
        (effects (font (size 0.25 0.25) (thickness 0.04)) (justify mirror))
    )
    (fp_text user "License: Apache-2.0" (at -0.939 -5.799) (layer "B.Fab") hide
        (effects (font (size 0.7 0.7) (thickness 0.15)) (justify left bottom mirror))
    )
    (fp_rect (start -0.925 0.47) (end 0.925 -0.47)
      (stroke (width 0.05) (type default)) (fill none) (layer "B.CrtYd"))
    (fp_line (start -0.494 -0.248) (end -0.494 0.25)
      (stroke (width 0.15) (type solid)) (layer "B.Fab"))
    (fp_line (start -0.494 0.25) (end 0.504 0.25)
      (stroke (width 0.15) (type solid)) (layer "B.Fab"))
    (fp_line (start 0.504 -0.248) (end -0.494 -0.248)
      (stroke (width 0.15) (type solid)) (layer "B.Fab"))
    (fp_line (start 0.504 0.25) (end 0.504 -0.248)
      (stroke (width 0.15) (type solid)) (layer "B.Fab"))
    (pad "1" smd roundrect (at -0.48 0 180) (size 0.59 0.64) (layers "B.Cu" "B.Paste" "B.Mask") (roundrect_rratio 0.25)
      (net 1 "GND") (pintype "passive"))
    (pad "2" smd roundrect (at 0.48 0 180) (size 0.59 0.64) (layers "B.Cu" "B.Paste" "B.Mask") (roundrect_rratio 0.25)
      (net 672 "Net-(C76-Pad2)") (pintype "passive"))
  )
	(footprint "antmicro-footprints:C_0402_1005Metric" (layer "B.Cu")
    (at 95 82.5)
    (descr "Capacitor SMD 0402")
    (tags "capacitor SMD 0402")
    (property "Author" "Antmicro")
    (property "Dielectric" "X5R")
    (property "License" "Apache-2.0")
    (property "MPN" "GRM155R61H104KE14D")
    (property "Manufacturer" "Murata")
    (property "Public" "False")
    (property "Sheetfile" "ethernet.kicad_sch")
    (property "Sheetname" "Ethernet")
    (property "Val" "100n")
    (property "Voltage" "50V")
    (property "ki_description" "SMD Multilayer Ceramic Capacitor, 0.1 µF, 50 V, 0402 [1005 Metric], ± 10%, X5R, GRM Series")
    (property "ki_keywords" "0402, SMT, CAPACITOR, PASSIVE, CERAMIC, MLCC")
    (attr smd)
    (fp_text reference "C29" (at -0.1 -2.03) (layer "B.SilkS")
        (effects (font (size 0.7 0.7) (thickness 0.127)) (justify mirror))
    )
    (fp_text value "C_100n_0402" (at 0 -1.17) (layer "B.Fab")
        (effects (font (size 1 1) (thickness 0.15)) (justify mirror))
    )
    (fp_text user "License: Apache-2.0" (at -0.939 -5.799 180) (layer "B.Fab") hide
        (effects (font (size 0.7 0.7) (thickness 0.15)) (justify left bottom mirror))
    )
    (fp_text user "Author: Antmicro" (at -0.939 -3.399 180) (layer "B.Fab") hide
        (effects (font (size 0.7 0.7) (thickness 0.15)) (justify left bottom mirror))
    )
    (fp_text user "${REFERENCE}" (at 0 0) (layer "B.Fab")
        (effects (font (size 0.25 0.25) (thickness 0.04)) (justify mirror))
    )
    (fp_rect (start -0.925 0.47) (end 0.925 -0.47)
      (stroke (width 0.05) (type default)) (fill none) (layer "B.CrtYd"))
    (fp_line (start -0.494 -0.248) (end -0.494 0.25)
      (stroke (width 0.15) (type solid)) (layer "B.Fab"))
    (fp_line (start -0.494 0.25) (end 0.504 0.25)
      (stroke (width 0.15) (type solid)) (layer "B.Fab"))
    (fp_line (start 0.504 -0.248) (end -0.494 -0.248)
      (stroke (width 0.15) (type solid)) (layer "B.Fab"))
    (fp_line (start 0.504 0.25) (end 0.504 -0.248)
      (stroke (width 0.15) (type solid)) (layer "B.Fab"))
    (pad "1" smd roundrect (at -0.48 0) (size 0.59 0.64) (layers "B.Cu" "B.Paste" "B.Mask") (roundrect_rratio 0.25)
      (net 1 "GND") (pintype "passive"))
    (pad "2" smd roundrect (at 0.48 0) (size 0.59 0.64) (layers "B.Cu" "B.Paste" "B.Mask") (roundrect_rratio 0.25)
      (net 13 "Net-(J1-TRCT3)") (pintype "passive"))
  )
)
